# T6G (Grand Teton) — schematic netlist excerpt (pin names and nets, part order shuffled) for the footprints in the layout excerpt that follows; sources: Cadence DE-HDL packaged netlist, KiCad conversion of 04192023_DAF0TMB3IC0_F0TG_MB_C_brd_V02_OCP.brd

J99  SCONN288_DDR506112002KQ  IO  pkg DDR288S_1-1VXC  page 108
  VIN_BULK0  = P12V_MEM_CPU1
  RFU0  = NC
  VIN_MGMT  = P3V3_AUX
  HSCL  = I3C_SPD_DDRK_CPU1_SCL
  HSDA  = I3C_SPD_DDRK_CPU1_SDA
  VSS0  = GND
  DQ0_A  = M_K_CPU1_SA_DQ<0>
  VSS1  = GND
  DQ1_A  = M_K_CPU1_SA_DQ<1>
  VSS2  = GND
  DQS0_A_T  = M_K_CPU1_SA_DQS_DP<0>
  DQS0_A_C  = M_K_CPU1_SA_DQS_DN<0>
  VSS3  = GND
  DQ4_A  = M_K_CPU1_SA_DQ<4>
  VSS4  = GND
  DQ5_A  = M_K_CPU1_SA_DQ<5>
  VSS5  = GND
  DQ8_A  = M_K_CPU1_SA_DQ<8>
  VSS6  = GND
  DQ9_A  = M_K_CPU1_SA_DQ<9>
  VSS7  = GND
  DQS1_A_T  = M_K_CPU1_SA_DQS_DP<1>
  DQS1_A_C  = M_K_CPU1_SA_DQS_DN<1>
  VSS8  = GND
  DQ12_A  = M_K_CPU1_SA_DQ<12>
  VSS9  = GND
  DQ13_A  = M_K_CPU1_SA_DQ<13>
  VSS10  = GND
  DQ16_A  = M_K_CPU1_SA_DQ<16>
  VSS11  = GND
  DQ17_A  = M_K_CPU1_SA_DQ<17>
  VSS12  = GND
  DQS2_A_T  = M_K_CPU1_SA_DQS_DP<2>
  DQS2_A_C  = M_K_CPU1_SA_DQS_DN<2>
  VSS13  = GND
  DQ20_A  = M_K_CPU1_SA_DQ<20>
  VSS14  = GND
  DQ21_A  = M_K_CPU1_SA_DQ<21>
  VSS15  = GND
  DQ24_A  = M_K_CPU1_SA_DQ<24>
  VSS16  = GND
  DQ25_A  = M_K_CPU1_SA_DQ<25>
  VSS17  = GND
  DQS3_A_T  = M_K_CPU1_SA_DQS_DP<3>
  DQS3_A_C  = M_K_CPU1_SA_DQS_DN<3>
  VSS18  = GND
  DQ28_A  = M_K_CPU1_SA_DQ<28>
  VSS19  = GND
  DQ29_A  = M_K_CPU1_SA_DQ<29>
  VSS20  = GND
  CB0_A  = M_K_CPU1_SA_CB<0>
  VSS21  = GND
  CB1_A  = M_K_CPU1_SA_CB<1>
  VSS22  = GND
  DQS4_A_T  = M_K_CPU1_SA_DQS_DP<4>
  DQS4_A_C  = M_K_CPU1_SA_DQS_DN<4>
  VSS23  = GND
  CB4_A  = M_K_CPU1_SA_CB<4>
  VSS24  = GND
  CB5_A  = M_K_CPU1_SA_CB<5>
  VSS25  = GND
  ALERT_N  = M_K_CPU1_ALERT_N
  VSS26  = GND
  CS0_A_N  = M_K_CPU1_SA_CS_N<0>
  VSS27  = GND
  CA0_A  = M_K_CPU1_SA_CA<0>
  VSS28  = GND
  CA2_A  = M_K_CPU1_SA_CA<2>
  VSS29  = GND
  CA4_A  = M_K_CPU1_SA_CA<4>
  VSS30  = GND
  CA6_A  = M_K_CPU1_SA_CA<6>
  VSS31  = GND
  PAR_A  = M_K_CPU1_SA_PAR
  VSS32  = GND
  CA0_B  = M_K_CPU1_SB_CA<0>
  VSS33  = GND
  CA2_B  = M_K_CPU1_SB_CA<2>
  VSS34  = GND
  CA4_B  = M_K_CPU1_SB_CA<4>
  VSS35  = GND
  CA6_B  = M_K_CPU1_SB_CA<6>
  VSS36  = GND
  CS0_B_N  = M_K_CPU1_SB_CS_N<0>
  VSS37  = GND
  \lbd||rsp_a_n\  = M_K_CPU1_SA_RSP<0>
  \lbs||rsp_b_n\  = M_K_CPU1_SB_RSP<0>
  VSS38  = GND
  CB4_B  = M_K_CPU1_SB_CB<4>
  VSS39  = GND
  CB5_B  = M_K_CPU1_SB_CB<5>
  VSS40  = GND
  \dqs9_b_t||tdqs9_b_t||dbi4_b_n\  = M_K_CPU1_SB_DQS_DP<9>
  \dqs9_b_c||tdqs9_b_c\  = M_K_CPU1_SB_DQS_DN<9>
  VSS41  = GND
  CB0_B  = M_K_CPU1_SB_CB<0>
  VSS42  = GND
  CB1_B  = M_K_CPU1_SB_CB<1>
  VSS43  = GND
  DQ0_B  = M_K_CPU1_SB_DQ<0>
  VSS44  = GND
  DQ1_B  = M_K_CPU1_SB_DQ<1>
  VSS45  = GND
  DQS0_B_T  = M_K_CPU1_SB_DQS_DP<0>
  DQS0_B_C  = M_K_CPU1_SB_DQS_DN<0>
  VSS46  = GND
  DQ4_B  = M_K_CPU1_SB_DQ<4>
  VSS47  = GND
  DQ5_B  = M_K_CPU1_SB_DQ<5>
  VSS48  = GND
  DQ8_B  = M_K_CPU1_SB_DQ<8>
  VSS49  = GND
  DQ9_B  = M_K_CPU1_SB_DQ<9>
  VSS50  = GND
  DQS1_B_T  = M_K_CPU1_SB_DQS_DP<1>
  DQS1_B_C  = M_K_CPU1_SB_DQS_DN<1>
  VSS51  = GND
  DQ12_B  = M_K_CPU1_SB_DQ<12>
  VSS52  = GND
  DQ13_B  = M_K_CPU1_SB_DQ<13>
  VSS53  = GND
  DQ16_B  = M_K_CPU1_SB_DQ<16>
  VSS54  = GND
  DQ17_B  = M_K_CPU1_SB_DQ<17>
  VSS55  = GND
  DQS2_B_T  = M_K_CPU1_SB_DQS_DP<2>
  DQS2_B_C  = M_K_CPU1_SB_DQS_DN<2>
  VSS56  = GND
  DQ20_B  = M_K_CPU1_SB_DQ<20>
  VSS57  = GND
  DQ21_B  = M_K_CPU1_SB_DQ<21>
  VSS58  = GND
  DQ24_B  = M_K_CPU1_SB_DQ<24>
  VSS59  = GND
  DQ25_B  = M_K_CPU1_SB_DQ<25>
  VSS60  = GND
  DQS3_B_T  = M_K_CPU1_SB_DQS_DP<3>
  DQS3_B_C  = M_K_CPU1_SB_DQS_DN<3>
  VSS61  = GND
  DQ28_B  = M_K_CPU1_SB_DQ<28>
  VSS62  = GND
  DQ29_B  = M_K_CPU1_SB_DQ<29>
  VSS63  = GND
  RFU1  = NC
  VIN_BULK1  = P12V_MEM_CPU1
  VIN_BULK2  = P12V_MEM_CPU1
  \pwr_good||fail_n\  = PWRGD_CHK_CPU1_DIMM
  HAS  = PD_CHK_CPU1_DIMM_SAA
  RFU2  = NC
  RFU3  = NC
  VSS64  = GND
  DQ2_A  = M_K_CPU1_SA_DQ<2>
  VSS65  = GND
  DQ3_A  = M_K_CPU1_SA_DQ<3>
  VSS66  = GND
  \dqs5_a_c||tdqs5_a_c||dqs5_a_t||tdqs5_a_t\  = M_K_CPU1_SA_DQS_DN<5>
  \dqs5_a_t||tdqs5_a_t\  = M_K_CPU1_SA_DQS_DP<5>
  VSS67  = GND
  DQ6_A  = M_K_CPU1_SA_DQ<6>
  VSS68  = GND
  DQ7_A  = M_K_CPU1_SA_DQ<7>
  VSS69  = GND
  DQ10_A  = M_K_CPU1_SA_DQ<10>
  VSS70  = GND
  DQ11_A  = M_K_CPU1_SA_DQ<11>
  VSS71  = GND
  \dqs6_a_c||tdqs6_a_c||dqs6_a_t||tdqs6_a_t\  = M_K_CPU1_SA_DQS_DN<6>
  \dqs6_a_t||tdqs6_a_t\  = M_K_CPU1_SA_DQS_DP<6>
  VSS72  = GND
  DQ14_A  = M_K_CPU1_SA_DQ<14>
  VSS73  = GND
  DQ15_A  = M_K_CPU1_SA_DQ<15>
  VSS74  = GND
  DQ18_A  = M_K_CPU1_SA_DQ<18>
  VSS75  = GND
  DQ19_A  = M_K_CPU1_SA_DQ<19>
  VSS76  = GND
  \dqs7_a_c||tdqs7_a_c\  = M_K_CPU1_SA_DQS_DN<7>
  \dqs7_a_t||tdqs7_a_t\  = M_K_CPU1_SA_DQS_DP<7>
  VSS77  = GND
  DQ22_A  = M_K_CPU1_SA_DQ<22>
  VSS78  = GND
  DQ23_A  = M_K_CPU1_SA_DQ<23>
  VSS79  = GND
  DQ26_A  = M_K_CPU1_SA_DQ<26>
  VSS80  = GND
  DQ27_A  = M_K_CPU1_SA_DQ<27>
  VSS81  = GND
  \dqs8_a_c||tdqs8_a_c\  = M_K_CPU1_SA_DQS_DN<8>
  \dqs8_a_t||tdqs8_a_t\  = M_K_CPU1_SA_DQS_DP<8>
  VSS82  = GND
  DQ30_A  = M_K_CPU1_SA_DQ<30>
  VSS83  = GND
  DQ31_A  = M_K_CPU1_SA_DQ<31>
  VSS84  = GND
  CB2_A  = M_K_CPU1_SA_CB<2>
  VSS85  = GND
  CB3_A  = M_K_CPU1_SA_CB<3>
  VSS86  = GND
  \dqs9_a_c||tdqs9_a_c\  = M_K_CPU1_SA_DQS_DN<9>
  \dqs9_a_t||tdqs9_a_t\  = M_K_CPU1_SA_DQS_DP<9>
  VSS87  = GND
  CB6_A  = M_K_CPU1_SA_CB<6>
  VSS88  = GND
  CB7_A  = M_K_CPU1_SA_CB<7>
  VSS89  = GND
  RESET_N  = M_K_CPU1_RESET_N
  VSS90  = GND
  CS1_A_N  = M_K_CPU1_SA_CS_N<1>
  VSS91  = GND
  CA1_A  = M_K_CPU1_SA_CA<1>
  VSS92  = GND
  CA3_A  = M_K_CPU1_SA_CA<3>
  VSS93  = GND
  CA5_A  = M_K_CPU1_SA_CA<5>
  VSS94  = GND
  CK_T  = M_K_CPU1_CLK_DP<0>
  CK_C  = M_K_CPU1_CLK_DN<0>
  VSS95  = GND
  RFU4  = NC
  CA1_B  = M_K_CPU1_SB_CA<1>
  VSS96  = GND
  CA3_B  = M_K_CPU1_SB_CA<3>
  VSS97  = GND
  CA5_B  = M_K_CPU1_SB_CA<5>
  VSS98  = GND
  PAR_B  = M_K_CPU1_SB_PAR
  VSS99  = GND
  CS1_B_N  = M_K_CPU1_SB_CS_N<1>
  VSS100  = GND
  RFU5  = NC
  RFU6  = NC
  VSS101  = GND
  CB6_B  = M_K_CPU1_SB_CB<6>
  VSS102  = GND
  CB7_B  = M_K_CPU1_SB_CB<7>
  VSS103  = GND
  DQS4_B_C  = M_K_CPU1_SB_DQS_DN<4>
  DQS4_B_T  = M_K_CPU1_SB_DQS_DP<4>
  VSS104  = GND
  CB2_B  = M_K_CPU1_SB_CB<2>
  VSS105  = GND
  CB3_B  = M_K_CPU1_SB_CB<3>
  VSS106  = GND
  DQ2_B  = M_K_CPU1_SB_DQ<2>
  VSS107  = GND
  DQ3_B  = M_K_CPU1_SB_DQ<3>
  VSS108  = GND
  \dqs5_b_c||tdqs5_b_c\  = M_K_CPU1_SB_DQS_DN<5>
  \dqs5_b_t||tdqs5_b_t\  = M_K_CPU1_SB_DQS_DP<5>
  VSS109  = GND
  DQ6_B  = M_K_CPU1_SB_DQ<6>
  VSS110  = GND
  DQ7_B  = M_K_CPU1_SB_DQ<7>
  VSS111  = GND
  DQ10_B  = M_K_CPU1_SB_DQ<10>
  VSS112  = GND
  DQ11_B  = M_K_CPU1_SB_DQ<11>
  VSS113  = GND
  \dqs6_b_c||tdqs6_b_c\  = M_K_CPU1_SB_DQS_DN<6>
  \dqs6_b_t||tdqs6_b_t\  = M_K_CPU1_SB_DQS_DP<6>
  VSS114  = GND
  DQ14_B  = M_K_CPU1_SB_DQ<14>
  VSS115  = GND
  DQ15_B  = M_K_CPU1_SB_DQ<15>
  VSS116  = GND
  DQ18_B  = M_K_CPU1_SB_DQ<18>
  VSS117  = GND
  DQ19_B  = M_K_CPU1_SB_DQ<19>
  VSS118  = GND
  \dqs7_b_c||tdqs7_b_c\  = M_K_CPU1_SB_DQS_DN<7>
  \dqs7_b_t||tdqs7_b_t\  = M_K_CPU1_SB_DQS_DP<7>
  VSS119  = GND
  DQ22_B  = M_K_CPU1_SB_DQ<22>
  VSS120  = GND
  DQ23_B  = M_K_CPU1_SB_DQ<23>
  VSS121  = GND
  DQ26_B  = M_K_CPU1_SB_DQ<26>
  VSS122  = GND
  DQ27_B  = M_K_CPU1_SB_DQ<27>
  VSS123  = GND
  \dqs8_b_c||tdqs8_b_c\  = M_K_CPU1_SB_DQS_DN<8>
  \dqs8_b_t||tdqs8_b_t\  = M_K_CPU1_SB_DQS_DP<8>
  VSS124  = GND
  DQ30_B  = M_K_CPU1_SB_DQ<30>
  VSS125  = GND
  DQ31_B  = M_K_CPU1_SB_DQ<31>
  VSS126  = GND
  G1  = GND
  G2  = GND
  G3  = GND

(kicad_pcb
	(version 20260206)
	(generator "pcbnew")
	(generator_version "10.0")
	(general
		(thickness 1.6)
		(legacy_teardrops no)
	)
	(paper "A4")
	(title_block
		(title "04192023_DAF0TMB3IC0_F0TG_MB_C_brd_V02_OCP.brd")
		(comment 1 "Grand Teton / footprint 4555 of 8354 (J99), pads 139-184 of 291")
	)
	(layers
		(0 "F.Cu" signal "TOP")
		(4 "In1.Cu" signal "GND")
		(6 "In2.Cu" signal "IN1")
		(8 "In3.Cu" signal "GND1")
		(10 "In4.Cu" signal "IN2")
		(12 "In5.Cu" signal "GND2")
		(14 "In6.Cu" signal "IN3")
		(16 "In7.Cu" signal "GND3")
		(18 "In8.Cu" signal "VCC")
		(20 "In9.Cu" signal "VCC1")
		(22 "In10.Cu" signal "GND4")
		(24 "In11.Cu" signal "IN4")
		(26 "In12.Cu" signal "GND5")
		(28 "In13.Cu" signal "IN5")
		(30 "In14.Cu" signal "GND6")
		(32 "In15.Cu" signal "IN6")
		(34 "In16.Cu" signal "GND7")
		(2 "B.Cu" signal "BOTTOM")
		(9 "F.Adhes" user "F.Adhesive")
		(11 "B.Adhes" user "B.Adhesive")
		(13 "F.Paste" user "Package Geometry/Pastemask Top")
		(15 "B.Paste" user "Package Geometry/Pastemask Bottom")
		(5 "F.SilkS" user "Ref Des/Silkscreen Top")
		(7 "B.SilkS" user "Ref Des/Silkscreen Bottom")
		(1 "F.Mask" user "Board Geometry/Soldermask Top")
		(3 "B.Mask" user "Board Geometry/Soldermask Bottom")
		(17 "Dwgs.User" user "User.Drawings")
		(19 "Cmts.User" user "User.Comments")
		(21 "Eco1.User" user "User.Eco1")
		(23 "Eco2.User" user "User.Eco2")
		(25 "Edge.Cuts" user "Board Geometry/Outline")
		(27 "Margin" user)
		(31 "F.CrtYd" user "Package Geometry/Place Bound Top")
		(29 "B.CrtYd" user "Package Geometry/Place Bound Bottom")
		(35 "F.Fab" user "Ref Des/Assembly Top")
		(33 "B.Fab" user "Ref Des/Assembly Bottom")
	)
	(footprint ""
		(layer "F.Cu")
		(at 196.654166 -255.560322 180)
		(property "Reference" "J99"
			(at -0.4318 -81.730088 0)
			(unlocked yes)
			(layer "F.SilkS")
			(effects
				(font
					(size 0.7874 0.5842)
					(thickness 0.1524)
				)
			)
		)
		(property "Value" ""
			(at 0 0 180)
			(layer "F.Fab")
			(effects
				(font
					(size 1.27 1.27)
				)
			)
		)
		(duplicate_pad_numbers_are_jumpers no)
		(pad "139" smd rect
			(at -2.050034 59.075066 90)
			(size 0.519938 1.4986)
			(layers "F.Cu" "F.Mask" "F.Paste")
			(net "GND")
		)
		(pad "140" smd rect
			(at -2.050034 59.92495 90)
			(size 0.519938 1.4986)
			(layers "F.Cu" "F.Mask" "F.Paste")
			(net "M_K_CPU1_SB_DQ<28>")
		)
		(pad "141" smd rect
			(at -2.050034 60.775088 90)
			(size 0.519938 1.4986)
			(layers "F.Cu" "F.Mask" "F.Paste")
			(net "GND")
		)
		(pad "142" smd rect
			(at -2.050034 61.624972 90)
			(size 0.519938 1.4986)
			(layers "F.Cu" "F.Mask" "F.Paste")
			(net "M_K_CPU1_SB_DQ<29>")
		)
		(pad "143" smd rect
			(at -2.050034 62.47511 90)
			(size 0.519938 1.4986)
			(layers "F.Cu" "F.Mask" "F.Paste")
			(net "GND")
		)
		(pad "144" smd rect
			(at -2.050034 63.324994 90)
			(size 0.519938 1.4986)
			(layers "F.Cu" "F.Mask" "F.Paste")
			(net "Net_2397")
		)
		(pad "145" smd rect
			(at 2.050034 -63.324994 90)
			(size 0.519938 1.4986)
			(layers "F.Cu" "F.Mask" "F.Paste")
			(net "P12V_MEM_CPU1")
		)
		(pad "146" smd rect
			(at 2.050034 -62.47511 90)
			(size 0.519938 1.4986)
			(layers "F.Cu" "F.Mask" "F.Paste")
			(net "P12V_MEM_CPU1")
		)
		(pad "147" smd rect
			(at 2.050034 -61.624972 90)
			(size 0.519938 1.4986)
			(layers "F.Cu" "F.Mask" "F.Paste")
			(net "PWRGD_CHK_CPU1_DIMM")
		)
		(pad "148" smd rect
			(at 2.050034 -60.775088 90)
			(size 0.519938 1.4986)
			(layers "F.Cu" "F.Mask" "F.Paste")
			(net "PD_CHK_CPU1_DIMM_SAA")
		)
		(pad "149" smd rect
			(at 2.050034 -59.92495 90)
			(size 0.519938 1.4986)
			(layers "F.Cu" "F.Mask" "F.Paste")
			(net "Net_2398")
		)
		(pad "150" smd rect
			(at 2.050034 -59.075066 90)
			(size 0.519938 1.4986)
			(layers "F.Cu" "F.Mask" "F.Paste")
			(net "Net_2399")
		)
		(pad "151" smd rect
			(at 2.050034 -58.224928 90)
			(size 0.519938 1.4986)
			(layers "F.Cu" "F.Mask" "F.Paste")
			(net "GND")
		)
		(pad "152" smd rect
			(at 2.050034 -57.375044 90)
			(size 0.519938 1.4986)
			(layers "F.Cu" "F.Mask" "F.Paste")
			(net "M_K_CPU1_SA_DQ<2>")
		)
		(pad "153" smd rect
			(at 2.050034 -56.524906 90)
			(size 0.519938 1.4986)
			(layers "F.Cu" "F.Mask" "F.Paste")
			(net "GND")
		)
		(pad "154" smd rect
			(at 2.050034 -55.675022 90)
			(size 0.519938 1.4986)
			(layers "F.Cu" "F.Mask" "F.Paste")
			(net "M_K_CPU1_SA_DQ<3>")
		)
		(pad "155" smd rect
			(at 2.050034 -54.824884 90)
			(size 0.519938 1.4986)
			(layers "F.Cu" "F.Mask" "F.Paste")
			(net "GND")
		)
		(pad "156" smd rect
			(at 2.050034 -53.975 90)
			(size 0.519938 1.4986)
			(layers "F.Cu" "F.Mask" "F.Paste")
			(net "M_K_CPU1_SA_DQS_DN<5>")
		)
		(pad "157" smd rect
			(at 2.050034 -53.125116 90)
			(size 0.519938 1.4986)
			(layers "F.Cu" "F.Mask" "F.Paste")
			(net "M_K_CPU1_SA_DQS_DP<5>")
		)
		(pad "158" smd rect
			(at 2.050034 -52.274978 90)
			(size 0.519938 1.4986)
			(layers "F.Cu" "F.Mask" "F.Paste")
			(net "GND")
		)
		(pad "159" smd rect
			(at 2.050034 -51.425094 90)
			(size 0.519938 1.4986)
			(layers "F.Cu" "F.Mask" "F.Paste")
			(net "M_K_CPU1_SA_DQ<6>")
		)
		(pad "160" smd rect
			(at 2.050034 -50.574956 90)
			(size 0.519938 1.4986)
			(layers "F.Cu" "F.Mask" "F.Paste")
			(net "GND")
		)
		(pad "161" smd rect
			(at 2.050034 -49.725072 90)
			(size 0.519938 1.4986)
			(layers "F.Cu" "F.Mask" "F.Paste")
			(net "M_K_CPU1_SA_DQ<7>")
		)
		(pad "162" smd rect
			(at 2.050034 -48.874934 90)
			(size 0.519938 1.4986)
			(layers "F.Cu" "F.Mask" "F.Paste")
			(net "GND")
		)
		(pad "163" smd rect
			(at 2.050034 -48.02505 90)
			(size 0.519938 1.4986)
			(layers "F.Cu" "F.Mask" "F.Paste")
			(net "M_K_CPU1_SA_DQ<10>")
		)
		(pad "164" smd rect
			(at 2.050034 -47.174912 90)
			(size 0.519938 1.4986)
			(layers "F.Cu" "F.Mask" "F.Paste")
			(net "GND")
		)
		(pad "165" smd rect
			(at 2.050034 -46.325028 90)
			(size 0.519938 1.4986)
			(layers "F.Cu" "F.Mask" "F.Paste")
			(net "M_K_CPU1_SA_DQ<11>")
		)
		(pad "166" smd rect
			(at 2.050034 -45.47489 90)
			(size 0.519938 1.4986)
			(layers "F.Cu" "F.Mask" "F.Paste")
			(net "GND")
		)
		(pad "167" smd rect
			(at 2.050034 -44.625006 90)
			(size 0.519938 1.4986)
			(layers "F.Cu" "F.Mask" "F.Paste")
			(net "M_K_CPU1_SA_DQS_DN<6>")
		)
		(pad "168" smd rect
			(at 2.050034 -43.775122 90)
			(size 0.519938 1.4986)
			(layers "F.Cu" "F.Mask" "F.Paste")
			(net "M_K_CPU1_SA_DQS_DP<6>")
		)
		(pad "169" smd rect
			(at 2.050034 -42.924984 90)
			(size 0.519938 1.4986)
			(layers "F.Cu" "F.Mask" "F.Paste")
			(net "GND")
		)
		(pad "170" smd rect
			(at 2.050034 -42.0751 90)
			(size 0.519938 1.4986)
			(layers "F.Cu" "F.Mask" "F.Paste")
			(net "M_K_CPU1_SA_DQ<14>")
		)
		(pad "171" smd rect
			(at 2.050034 -41.224962 90)
			(size 0.519938 1.4986)
			(layers "F.Cu" "F.Mask" "F.Paste")
			(net "GND")
		)
		(pad "172" smd rect
			(at 2.050034 -40.375078 90)
			(size 0.519938 1.4986)
			(layers "F.Cu" "F.Mask" "F.Paste")
			(net "M_K_CPU1_SA_DQ<15>")
		)
		(pad "173" smd rect
			(at 2.050034 -39.52494 90)
			(size 0.519938 1.4986)
			(layers "F.Cu" "F.Mask" "F.Paste")
			(net "GND")
		)
		(pad "174" smd rect
			(at 2.050034 -38.675056 90)
			(size 0.519938 1.4986)
			(layers "F.Cu" "F.Mask" "F.Paste")
			(net "M_K_CPU1_SA_DQ<18>")
		)
		(pad "175" smd rect
			(at 2.050034 -37.824918 90)
			(size 0.519938 1.4986)
			(layers "F.Cu" "F.Mask" "F.Paste")
			(net "GND")
		)
		(pad "176" smd rect
			(at 2.050034 -36.975034 90)
			(size 0.519938 1.4986)
			(layers "F.Cu" "F.Mask" "F.Paste")
			(net "M_K_CPU1_SA_DQ<19>")
		)
		(pad "177" smd rect
			(at 2.050034 -36.124896 90)
			(size 0.519938 1.4986)
			(layers "F.Cu" "F.Mask" "F.Paste")
			(net "GND")
		)
		(pad "178" smd rect
			(at 2.050034 -35.275012 90)
			(size 0.519938 1.4986)
			(layers "F.Cu" "F.Mask" "F.Paste")
			(net "M_K_CPU1_SA_DQS_DN<7>")
		)
		(pad "179" smd rect
			(at 2.050034 -34.425128 90)
			(size 0.519938 1.4986)
			(layers "F.Cu" "F.Mask" "F.Paste")
			(net "M_K_CPU1_SA_DQS_DP<7>")
		)
		(pad "180" smd rect
			(at 2.050034 -33.57499 90)
			(size 0.519938 1.4986)
			(layers "F.Cu" "F.Mask" "F.Paste")
			(net "GND")
		)
		(pad "181" smd rect
			(at 2.050034 -32.725106 90)
			(size 0.519938 1.4986)
			(layers "F.Cu" "F.Mask" "F.Paste")
			(net "M_K_CPU1_SA_DQ<22>")
		)
		(pad "182" smd rect
			(at 2.050034 -31.874968 90)
			(size 0.519938 1.4986)
			(layers "F.Cu" "F.Mask" "F.Paste")
			(net "GND")
		)
		(pad "183" smd rect
			(at 2.050034 -31.025084 90)
			(size 0.519938 1.4986)
			(layers "F.Cu" "F.Mask" "F.Paste")
			(net "M_K_CPU1_SA_DQ<23>")
		)
		(pad "184" smd rect
			(at 2.050034 -30.174946 90)
			(size 0.519938 1.4986)
			(layers "F.Cu" "F.Mask" "F.Paste")
			(net "GND")
		)
	)
)
